(kicad_pcb
	(version 20260206)
	(generator "pcbnew")
	(generator_version "10.0")
	(general
		(thickness 1.6)
		(legacy_teardrops no)
	)
	(paper "A4")
	(title_block
		(title "03242023_DA0F0TMBIJ0_F0T_Motherboard_J_brd_V01_OCP.brd")
		(comment 1 "Grand Teton / footprints 854-860 of 6105")
	)
	(layers
		(0 "F.Cu" signal "TOP")
		(4 "In1.Cu" signal "GND")
		(6 "In2.Cu" signal "IN1")
		(8 "In3.Cu" signal "GND1")
		(10 "In4.Cu" signal "IN2")
		(12 "In5.Cu" signal "GND2")
		(14 "In6.Cu" signal "IN3")
		(16 "In7.Cu" signal "GND3")
		(18 "In8.Cu" signal "VCC")
		(20 "In9.Cu" signal "VCC1")
		(22 "In10.Cu" signal "GND4")
		(24 "In11.Cu" signal "IN4")
		(26 "In12.Cu" signal "GND5")
		(28 "In13.Cu" signal "IN5")
		(30 "In14.Cu" signal "GND6")
		(32 "In15.Cu" signal "IN6")
		(34 "In16.Cu" signal "GND7")
		(2 "B.Cu" signal "BOTTOM")
		(9 "F.Adhes" user "F.Adhesive")
		(11 "B.Adhes" user "B.Adhesive")
		(13 "F.Paste" user "Package Geometry/Pastemask Top")
		(15 "B.Paste" user "Package Geometry/Pastemask Bottom")
		(5 "F.SilkS" user "Ref Des/Silkscreen Top")
		(7 "B.SilkS" user "Ref Des/Silkscreen Bottom")
		(1 "F.Mask" user "Board Geometry/Soldermask Top")
		(3 "B.Mask" user "Board Geometry/Soldermask Bottom")
		(17 "Dwgs.User" user "User.Drawings")
		(19 "Cmts.User" user "User.Comments")
		(21 "Eco1.User" user "User.Eco1")
		(23 "Eco2.User" user "User.Eco2")
		(25 "Edge.Cuts" user "Board Geometry/Outline")
		(27 "Margin" user)
		(31 "F.CrtYd" user "Package Geometry/Place Bound Top")
		(29 "B.CrtYd" user "Package Geometry/Place Bound Bottom")
		(35 "F.Fab" user "Ref Des/Assembly Top")
		(33 "B.Fab" user "Ref Des/Assembly Bottom")
	)
	(footprint ""
		(layer "F.Cu")
		(at 131.32308 -21.554948 90)
		(property "Reference" "R3254"
			(at 0 0 90)
			(layer "F.SilkS")
			(hide yes)
			(effects
				(font
					(size 1.27 1.27)
				)
			)
		)
		(property "Value" ""
			(at 0 0 90)
			(layer "F.Fab")
			(effects
				(font
					(size 1.27 1.27)
				)
			)
		)
		(duplicate_pad_numbers_are_jumpers no)
		(fp_line
			(start 0.7874 -0.4064)
			(end 0.7874 0.4064)
			(stroke
				(width 0.1524)
				(type default)
			)
			(layer "F.SilkS")
		)
		(fp_line
			(start -0.7874 -0.4064)
			(end 0.7874 -0.4064)
			(stroke
				(width 0.1524)
				(type default)
			)
			(layer "F.SilkS")
		)
		(fp_line
			(start 0.7874 0.4064)
			(end -0.7874 0.4064)
			(stroke
				(width 0.1524)
				(type default)
			)
			(layer "F.SilkS")
		)
		(fp_line
			(start -0.7874 0.4064)
			(end -0.7874 -0.4064)
			(stroke
				(width 0.1524)
				(type default)
			)
			(layer "F.SilkS")
		)
		(fp_line
			(start -0.12065 -0.305054)
			(end -0.12065 -0.2794)
			(stroke
				(width 0.1)
				(type default)
			)
			(layer "F.Fab")
		)
		(fp_line
			(start -0.67945 -0.305054)
			(end -0.12065 -0.305054)
			(stroke
				(width 0.1)
				(type default)
			)
			(layer "F.Fab")
		)
		(fp_line
			(start 0.67945 -0.3048)
			(end 0.67945 0.3048)
			(stroke
				(width 0.1)
				(type default)
			)
			(layer "F.Fab")
		)
		(fp_line
			(start 0.12065 -0.3048)
			(end 0.67945 -0.3048)
			(stroke
				(width 0.1)
				(type default)
			)
			(layer "F.Fab")
		)
		(fp_line
			(start 0.12065 -0.2794)
			(end 0.12065 -0.3048)
			(stroke
				(width 0.1)
				(type default)
			)
			(layer "F.Fab")
		)
		(fp_line
			(start -0.12065 -0.2794)
			(end 0.12065 -0.2794)
			(stroke
				(width 0.1)
				(type default)
			)
			(layer "F.Fab")
		)
		(fp_line
			(start 0.120396 0.2794)
			(end -0.12065 0.2794)
			(stroke
				(width 0.1)
				(type default)
			)
			(layer "F.Fab")
		)
		(fp_line
			(start -0.12065 0.2794)
			(end -0.12065 0.3048)
			(stroke
				(width 0.1)
				(type default)
			)
			(layer "F.Fab")
		)
		(fp_line
			(start 0.67945 0.3048)
			(end 0.120396 0.3048)
			(stroke
				(width 0.1)
				(type default)
			)
			(layer "F.Fab")
		)
		(fp_line
			(start 0.120396 0.3048)
			(end 0.120396 0.2794)
			(stroke
				(width 0.1)
				(type default)
			)
			(layer "F.Fab")
		)
		(fp_line
			(start -0.12065 0.3048)
			(end -0.67945 0.3048)
			(stroke
				(width 0.1)
				(type default)
			)
			(layer "F.Fab")
		)
		(fp_line
			(start -0.67945 0.3048)
			(end -0.67945 -0.305054)
			(stroke
				(width 0.1)
				(type default)
			)
			(layer "F.Fab")
		)
		(pad "1" smd circle
			(at -0.40005 0 90)
			(size 0 0)
			(layers "F.Cu" "F.Mask" "F.Paste")
			(net "TP_PCIE_HPM_TXP<3>")
		)
		(pad "2" smd circle
			(at 0.40005 0 90)
			(size 0 0)
			(layers "F.Cu" "F.Mask" "F.Paste")
			(net "LED_HDD_ACTIVITY_B_N")
		)
	)
	(footprint ""
		(layer "F.Cu")
		(at 129.159 -53.304948)
		(property "Reference" "R4631"
			(at 0 0 0)
			(layer "F.SilkS")
			(hide yes)
			(effects
				(font
					(size 1.27 1.27)
				)
			)
		)
		(property "Value" ""
			(at 0 0 0)
			(layer "F.Fab")
			(effects
				(font
					(size 1.27 1.27)
				)
			)
		)
		(duplicate_pad_numbers_are_jumpers no)
		(fp_line
			(start -0.7874 -0.4064)
			(end 0.7874 -0.4064)
			(stroke
				(width 0.1524)
				(type default)
			)
			(layer "F.SilkS")
		)
		(fp_line
			(start -0.7874 0.4064)
			(end -0.7874 -0.4064)
			(stroke
				(width 0.1524)
				(type default)
			)
			(layer "F.SilkS")
		)
		(fp_line
			(start 0.7874 -0.4064)
			(end 0.7874 0.4064)
			(stroke
				(width 0.1524)
				(type default)
			)
			(layer "F.SilkS")
		)
		(fp_line
			(start 0.7874 0.4064)
			(end -0.7874 0.4064)
			(stroke
				(width 0.1524)
				(type default)
			)
			(layer "F.SilkS")
		)
		(fp_line
			(start -0.67945 -0.305054)
			(end -0.12065 -0.305054)
			(stroke
				(width 0.1)
				(type default)
			)
			(layer "F.Fab")
		)
		(fp_line
			(start -0.67945 0.3048)
			(end -0.67945 -0.305054)
			(stroke
				(width 0.1)
				(type default)
			)
			(layer "F.Fab")
		)
		(fp_line
			(start -0.12065 -0.305054)
			(end -0.12065 -0.2794)
			(stroke
				(width 0.1)
				(type default)
			)
			(layer "F.Fab")
		)
		(fp_line
			(start -0.12065 -0.2794)
			(end 0.12065 -0.2794)
			(stroke
				(width 0.1)
				(type default)
			)
			(layer "F.Fab")
		)
		(fp_line
			(start -0.12065 0.2794)
			(end -0.12065 0.3048)
			(stroke
				(width 0.1)
				(type default)
			)
			(layer "F.Fab")
		)
		(fp_line
			(start -0.12065 0.3048)
			(end -0.67945 0.3048)
			(stroke
				(width 0.1)
				(type default)
			)
			(layer "F.Fab")
		)
		(fp_line
			(start 0.120396 0.2794)
			(end -0.12065 0.2794)
			(stroke
				(width 0.1)
				(type default)
			)
			(layer "F.Fab")
		)
		(fp_line
			(start 0.120396 0.3048)
			(end 0.120396 0.2794)
			(stroke
				(width 0.1)
				(type default)
			)
			(layer "F.Fab")
		)
		(fp_line
			(start 0.12065 -0.3048)
			(end 0.67945 -0.3048)
			(stroke
				(width 0.1)
				(type default)
			)
			(layer "F.Fab")
		)
		(fp_line
			(start 0.12065 -0.2794)
			(end 0.12065 -0.3048)
			(stroke
				(width 0.1)
				(type default)
			)
			(layer "F.Fab")
		)
		(fp_line
			(start 0.67945 -0.3048)
			(end 0.67945 0.3048)
			(stroke
				(width 0.1)
				(type default)
			)
			(layer "F.Fab")
		)
		(fp_line
			(start 0.67945 0.3048)
			(end 0.120396 0.3048)
			(stroke
				(width 0.1)
				(type default)
			)
			(layer "F.Fab")
		)
		(pad "1" smd circle
			(at -0.40005 0)
			(size 0 0)
			(layers "F.Cu" "F.Mask" "F.Paste")
			(net "JTAG_BMC_SW_TDI_R")
		)
		(pad "2" smd circle
			(at 0.40005 0)
			(size 0 0)
			(layers "F.Cu" "F.Mask" "F.Paste")
			(net "JTAG_BMC_SW_TDI")
		)
	)
	(footprint ""
		(layer "F.Cu")
		(at 437.425846 -387.527292 180)
		(property "Reference" "PC1845"
			(at 0 0 180)
			(layer "F.SilkS")
			(hide yes)
			(effects
				(font
					(size 1.27 1.27)
				)
			)
		)
		(property "Value" ""
			(at 0 0 180)
			(layer "F.Fab")
			(effects
				(font
					(size 1.27 1.27)
				)
			)
		)
		(duplicate_pad_numbers_are_jumpers no)
		(fp_line
			(start 2.750058 2.750058)
			(end 2.750058 0.9398)
			(stroke
				(width 0.1524)
				(type default)
			)
			(layer "F.SilkS")
		)
		(fp_line
			(start 2.750058 -0.9398)
			(end 2.750058 -2.750058)
			(stroke
				(width 0.1524)
				(type default)
			)
			(layer "F.SilkS")
		)
		(fp_line
			(start 2.750058 -2.750058)
			(end -1.988058 -2.750058)
			(stroke
				(width 0.1524)
				(type default)
			)
			(layer "F.SilkS")
		)
		(fp_line
			(start -1.988058 2.750058)
			(end 2.750058 2.750058)
			(stroke
				(width 0.1524)
				(type default)
			)
			(layer "F.SilkS")
		)
		(fp_line
			(start -1.988058 -2.750058)
			(end -2.750058 -1.988058)
			(stroke
				(width 0.1524)
				(type default)
			)
			(layer "F.SilkS")
		)
		(fp_line
			(start -2.750058 1.988058)
			(end -1.988058 2.750058)
			(stroke
				(width 0.1524)
				(type default)
			)
			(layer "F.SilkS")
		)
		(fp_line
			(start -2.750058 0.9398)
			(end -2.750058 1.988058)
			(stroke
				(width 0.1524)
				(type default)
			)
			(layer "F.SilkS")
		)
		(fp_line
			(start -2.750058 -1.988058)
			(end -2.750058 -0.9398)
			(stroke
				(width 0.1524)
				(type default)
			)
			(layer "F.SilkS")
		)
		(fp_line
			(start 2.750058 2.750058)
			(end 2.750058 -2.750058)
			(stroke
				(width 0.1)
				(type default)
			)
			(layer "F.Fab")
		)
		(fp_line
			(start 2.750058 -2.750058)
			(end -2.750058 -2.750058)
			(stroke
				(width 0.1)
				(type default)
			)
			(layer "F.Fab")
		)
		(fp_line
			(start -2.750058 2.750058)
			(end 2.750058 2.750058)
			(stroke
				(width 0.1)
				(type default)
			)
			(layer "F.Fab")
		)
		(fp_line
			(start -2.750058 -2.750058)
			(end -2.750058 2.750058)
			(stroke
				(width 0.1)
				(type default)
			)
			(layer "F.Fab")
		)
		(pad "1" smd rect
			(at -2.199894 0 270)
			(size 1.6002 3.0226)
			(layers "F.Cu" "F.Mask" "F.Paste")
			(net "P5V_AUX")
		)
		(pad "2" smd rect
			(at 2.199894 0 270)
			(size 1.6002 3.0226)
			(layers "F.Cu" "F.Mask" "F.Paste")
			(net "GND")
		)
	)
	(footprint ""
		(layer "F.Cu")
		(at 164.361114 -408.517344 -90)
		(property "Reference" "C1544"
			(at 0 0 270)
			(layer "F.SilkS")
			(hide yes)
			(effects
				(font
					(size 1.27 1.27)
				)
			)
		)
		(property "Value" ""
			(at 0 0 270)
			(layer "F.Fab")
			(effects
				(font
					(size 1.27 1.27)
				)
			)
		)
		(duplicate_pad_numbers_are_jumpers no)
		(fp_line
			(start -0.299974 0.150114)
			(end -0.299974 -0.150114)
			(stroke
				(width 0.1)
				(type default)
			)
			(layer "F.Fab")
		)
		(fp_line
			(start 0.299974 0.150114)
			(end -0.299974 0.150114)
			(stroke
				(width 0.1)
				(type default)
			)
			(layer "F.Fab")
		)
		(fp_line
			(start -0.299974 -0.150114)
			(end 0.299974 -0.150114)
			(stroke
				(width 0.1)
				(type default)
			)
			(layer "F.Fab")
		)
		(fp_line
			(start 0.299974 -0.150114)
			(end 0.299974 0.150114)
			(stroke
				(width 0.1)
				(type default)
			)
			(layer "F.Fab")
		)
		(pad "1" smd rect
			(at -0.2667 0 270)
			(size 0.3048 0.381)
			(layers "F.Cu" "F.Mask" "F.Paste")
			(net "P5E_CPU1_PE3_TX_C_DN<1>")
		)
		(pad "2" smd rect
			(at 0.2667 0 270)
			(size 0.3048 0.381)
			(layers "F.Cu" "F.Mask" "F.Paste")
			(net "P5E_CPU1_PE3_TX_DN<1>")
		)
	)
	(footprint ""
		(layer "F.Cu")
		(at 417.66744 -51.87696 90)
		(property "Reference" "R4681"
			(at 0 0 90)
			(layer "F.SilkS")
			(hide yes)
			(effects
				(font
					(size 1.27 1.27)
				)
			)
		)
		(property "Value" ""
			(at 0 0 90)
			(layer "F.Fab")
			(effects
				(font
					(size 1.27 1.27)
				)
			)
		)
		(duplicate_pad_numbers_are_jumpers no)
		(fp_line
			(start 0.7874 -0.4064)
			(end 0.7874 0.4064)
			(stroke
				(width 0.1524)
				(type default)
			)
			(layer "F.SilkS")
		)
		(fp_line
			(start -0.7874 -0.4064)
			(end 0.7874 -0.4064)
			(stroke
				(width 0.1524)
				(type default)
			)
			(layer "F.SilkS")
		)
		(fp_line
			(start 0.7874 0.4064)
			(end -0.7874 0.4064)
			(stroke
				(width 0.1524)
				(type default)
			)
			(layer "F.SilkS")
		)
		(fp_line
			(start -0.7874 0.4064)
			(end -0.7874 -0.4064)
			(stroke
				(width 0.1524)
				(type default)
			)
			(layer "F.SilkS")
		)
		(fp_line
			(start -0.12065 -0.305054)
			(end -0.12065 -0.2794)
			(stroke
				(width 0.1)
				(type default)
			)
			(layer "F.Fab")
		)
		(fp_line
			(start -0.67945 -0.305054)
			(end -0.12065 -0.305054)
			(stroke
				(width 0.1)
				(type default)
			)
			(layer "F.Fab")
		)
		(fp_line
			(start 0.67945 -0.3048)
			(end 0.67945 0.3048)
			(stroke
				(width 0.1)
				(type default)
			)
			(layer "F.Fab")
		)
		(fp_line
			(start 0.12065 -0.3048)
			(end 0.67945 -0.3048)
			(stroke
				(width 0.1)
				(type default)
			)
			(layer "F.Fab")
		)
		(fp_line
			(start 0.12065 -0.2794)
			(end 0.12065 -0.3048)
			(stroke
				(width 0.1)
				(type default)
			)
			(layer "F.Fab")
		)
		(fp_line
			(start -0.12065 -0.2794)
			(end 0.12065 -0.2794)
			(stroke
				(width 0.1)
				(type default)
			)
			(layer "F.Fab")
		)
		(fp_line
			(start 0.120396 0.2794)
			(end -0.12065 0.2794)
			(stroke
				(width 0.1)
				(type default)
			)
			(layer "F.Fab")
		)
		(fp_line
			(start -0.12065 0.2794)
			(end -0.12065 0.3048)
			(stroke
				(width 0.1)
				(type default)
			)
			(layer "F.Fab")
		)
		(fp_line
			(start 0.67945 0.3048)
			(end 0.120396 0.3048)
			(stroke
				(width 0.1)
				(type default)
			)
			(layer "F.Fab")
		)
		(fp_line
			(start 0.120396 0.3048)
			(end 0.120396 0.2794)
			(stroke
				(width 0.1)
				(type default)
			)
			(layer "F.Fab")
		)
		(fp_line
			(start -0.12065 0.3048)
			(end -0.67945 0.3048)
			(stroke
				(width 0.1)
				(type default)
			)
			(layer "F.Fab")
		)
		(fp_line
			(start -0.67945 0.3048)
			(end -0.67945 -0.305054)
			(stroke
				(width 0.1)
				(type default)
			)
			(layer "F.Fab")
		)
		(pad "1" smd circle
			(at -0.40005 0 90)
			(size 0 0)
			(layers "F.Cu" "F.Mask" "F.Paste")
			(net "PWRGD_P3V3_R1")
		)
		(pad "2" smd circle
			(at 0.40005 0 90)
			(size 0 0)
			(layers "F.Cu" "F.Mask" "F.Paste")
			(net "GND")
		)
	)
	(footprint ""
		(layer "F.Cu")
		(at 210.560412 -98.809048)
		(property "Reference" "R2219"
			(at 0 0 0)
			(layer "F.SilkS")
			(hide yes)
			(effects
				(font
					(size 1.27 1.27)
				)
			)
		)
		(property "Value" ""
			(at 0 0 0)
			(layer "F.Fab")
			(effects
				(font
					(size 1.27 1.27)
				)
			)
		)
		(duplicate_pad_numbers_are_jumpers no)
		(fp_line
			(start -0.7874 -0.4064)
			(end 0.7874 -0.4064)
			(stroke
				(width 0.1524)
				(type default)
			)
			(layer "F.SilkS")
		)
		(fp_line
			(start -0.7874 0.4064)
			(end -0.7874 -0.4064)
			(stroke
				(width 0.1524)
				(type default)
			)
			(layer "F.SilkS")
		)
		(fp_line
			(start 0.7874 -0.4064)
			(end 0.7874 0.4064)
			(stroke
				(width 0.1524)
				(type default)
			)
			(layer "F.SilkS")
		)
		(fp_line
			(start 0.7874 0.4064)
			(end -0.7874 0.4064)
			(stroke
				(width 0.1524)
				(type default)
			)
			(layer "F.SilkS")
		)
		(fp_line
			(start -0.67945 -0.305054)
			(end -0.12065 -0.305054)
			(stroke
				(width 0.1)
				(type default)
			)
			(layer "F.Fab")
		)
		(fp_line
			(start -0.67945 0.3048)
			(end -0.67945 -0.305054)
			(stroke
				(width 0.1)
				(type default)
			)
			(layer "F.Fab")
		)
		(fp_line
			(start -0.12065 -0.305054)
			(end -0.12065 -0.2794)
			(stroke
				(width 0.1)
				(type default)
			)
			(layer "F.Fab")
		)
		(fp_line
			(start -0.12065 -0.2794)
			(end 0.12065 -0.2794)
			(stroke
				(width 0.1)
				(type default)
			)
			(layer "F.Fab")
		)
		(fp_line
			(start -0.12065 0.2794)
			(end -0.12065 0.3048)
			(stroke
				(width 0.1)
				(type default)
			)
			(layer "F.Fab")
		)
		(fp_line
			(start -0.12065 0.3048)
			(end -0.67945 0.3048)
			(stroke
				(width 0.1)
				(type default)
			)
			(layer "F.Fab")
		)
		(fp_line
			(start 0.120396 0.2794)
			(end -0.12065 0.2794)
			(stroke
				(width 0.1)
				(type default)
			)
			(layer "F.Fab")
		)
		(fp_line
			(start 0.120396 0.3048)
			(end 0.120396 0.2794)
			(stroke
				(width 0.1)
				(type default)
			)
			(layer "F.Fab")
		)
		(fp_line
			(start 0.12065 -0.3048)
			(end 0.67945 -0.3048)
			(stroke
				(width 0.1)
				(type default)
			)
			(layer "F.Fab")
		)
		(fp_line
			(start 0.12065 -0.2794)
			(end 0.12065 -0.3048)
			(stroke
				(width 0.1)
				(type default)
			)
			(layer "F.Fab")
		)
		(fp_line
			(start 0.67945 -0.3048)
			(end 0.67945 0.3048)
			(stroke
				(width 0.1)
				(type default)
			)
			(layer "F.Fab")
		)
		(fp_line
			(start 0.67945 0.3048)
			(end 0.120396 0.3048)
			(stroke
				(width 0.1)
				(type default)
			)
			(layer "F.Fab")
		)
		(pad "1" smd circle
			(at -0.40005 0)
			(size 0 0)
			(layers "F.Cu" "F.Mask" "F.Paste")
			(net "P12V_AUX")
		)
		(pad "2" smd circle
			(at 0.40005 0)
			(size 0 0)
			(layers "F.Cu" "F.Mask" "F.Paste")
			(net "A_P12V_STBY_ADR_TRIGGER")
		)
	)
	(footprint ""
		(layer "F.Cu")
		(at 261.436612 -133.001512 180)
		(property "Reference" "R4497"
			(at 0 0 180)
			(layer "F.SilkS")
			(hide yes)
			(effects
				(font
					(size 1.27 1.27)
				)
			)
		)
		(property "Value" ""
			(at 0 0 180)
			(layer "F.Fab")
			(effects
				(font
					(size 1.27 1.27)
				)
			)
		)
		(duplicate_pad_numbers_are_jumpers no)
		(fp_line
			(start 0.7874 0.4064)
			(end -0.7874 0.4064)
			(stroke
				(width 0.1524)
				(type default)
			)
			(layer "F.SilkS")
		)
		(fp_line
			(start 0.7874 -0.4064)
			(end 0.7874 0.4064)
			(stroke
				(width 0.1524)
				(type default)
			)
			(layer "F.SilkS")
		)
		(fp_line
			(start -0.7874 0.4064)
			(end -0.7874 -0.4064)
			(stroke
				(width 0.1524)
				(type default)
			)
			(layer "F.SilkS")
		)
		(fp_line
			(start -0.7874 -0.4064)
			(end 0.7874 -0.4064)
			(stroke
				(width 0.1524)
				(type default)
			)
			(layer "F.SilkS")
		)
		(fp_line
			(start 0.67945 0.3048)
			(end 0.120396 0.3048)
			(stroke
				(width 0.1)
				(type default)
			)
			(layer "F.Fab")
		)
		(fp_line
			(start 0.67945 -0.3048)
			(end 0.67945 0.3048)
			(stroke
				(width 0.1)
				(type default)
			)
			(layer "F.Fab")
		)
		(fp_line
			(start 0.12065 -0.2794)
			(end 0.12065 -0.3048)
			(stroke
				(width 0.1)
				(type default)
			)
			(layer "F.Fab")
		)
		(fp_line
			(start 0.12065 -0.3048)
			(end 0.67945 -0.3048)
			(stroke
				(width 0.1)
				(type default)
			)
			(layer "F.Fab")
		)
		(fp_line
			(start 0.120396 0.3048)
			(end 0.120396 0.2794)
			(stroke
				(width 0.1)
				(type default)
			)
			(layer "F.Fab")
		)
		(fp_line
			(start 0.120396 0.2794)
			(end -0.12065 0.2794)
			(stroke
				(width 0.1)
				(type default)
			)
			(layer "F.Fab")
		)
		(fp_line
			(start -0.12065 0.3048)
			(end -0.67945 0.3048)
			(stroke
				(width 0.1)
				(type default)
			)
			(layer "F.Fab")
		)
		(fp_line
			(start -0.12065 0.2794)
			(end -0.12065 0.3048)
			(stroke
				(width 0.1)
				(type default)
			)
			(layer "F.Fab")
		)
		(fp_line
			(start -0.12065 -0.2794)
			(end 0.12065 -0.2794)
			(stroke
				(width 0.1)
				(type default)
			)
			(layer "F.Fab")
		)
		(fp_line
			(start -0.12065 -0.305054)
			(end -0.12065 -0.2794)
			(stroke
				(width 0.1)
				(type default)
			)
			(layer "F.Fab")
		)
		(fp_line
			(start -0.67945 0.3048)
			(end -0.67945 -0.305054)
			(stroke
				(width 0.1)
				(type default)
			)
			(layer "F.Fab")
		)
		(fp_line
			(start -0.67945 -0.305054)
			(end -0.12065 -0.305054)
			(stroke
				(width 0.1)
				(type default)
			)
			(layer "F.Fab")
		)
		(pad "1" smd circle
			(at -0.40005 0 180)
			(size 0 0)
			(layers "F.Cu" "F.Mask" "F.Paste")
			(net "SMB_HOST_CLK_BUF_ISO_3V3AUX_SDA")
		)
		(pad "2" smd circle
			(at 0.40005 0 180)
			(size 0 0)
			(layers "F.Cu" "F.Mask" "F.Paste")
			(net "SMB_HOST_DB2000_3V3AUX_SDA")
		)
	)
)
